FILE_TYPE = MACRO_DRAWING;
SET COLOR_WIRE YELLOW;
SET COLOR_PROP ORANGE;
SET COLOR_DOT WHITE;
SET COLOR_ARC YELLOW;
SET COLOR_BODY GREEN;
SET COLOR_NOTE PURPLE;
SET PROP_DISPLAY VALUE;
SET PAGE_NUMBER P446;
FORCEADD QUANTA_TITLE_BLOCK_C..1
(0 0);
FORCEPROP 1 LAST CUSTOM_TXT_CDS <NAME_2>
J 0
(-3175 50);
FORCEPROP 1 LAST CUSTOM_TXT_CDS <NAME_1>
J 0
(-3175 175);
FORCEPROP 1 LAST CUSTOM_TXT_CDS <Q_NUMBER>
J 0
(-1403 103);
DISPLAY 1.212766 (-1403 103);
FORCEPROP 1 LAST CUSTOM_TXT_CDS <Q_PROJ>
J 0
(-2382 102);
DISPLAY 1.212766 (-2382 102);
FORCEPROP 1 LAST CUSTOM_TXT_CDS <Q_REV>
J 0
(-184 103);
DISPLAY 1.212766 (-184 103);
FORCEPROP 1 LAST CUSTOM_TXT_CDS <CON_LAST_MODIFIED>
J 0
(-1885 15);
DISPLAY 0.978723 (-1885 15);
FORCEPROP 1 LAST CUSTOM_TXT_CDS <CON_PAGE_NUM> OF <CON_TOTAL_PAGES>
J 0
(-446 18);
DISPLAY 0.978723 (-446 18);
FORCEPROP 1 LAST Q_TITLE BLANK
J 0
(-9366 26);
DISPLAY 2.446809 (-9366 26);
PAINT GREEN (-9366 26);
FORCEPROP 2 LAST CDS_LIB pure_quanta
J 0
(0 0);
DISPLAY INVISIBLE (0 0);
FORCEPROP 1 LAST CDS_LMAN_SYM_OUTLINE -9475,6775,100,-125
J 0
(0 0);
DISPLAY 0.468085 (0 0);
PAINT GREEN (0 0);
DISPLAY INVISIBLE (0 0);
FORCEPROP 2 LAST PAGE_BORDER TRUE
J 0
(-7890 5250);
DISPLAY 0.638298 (-7890 5250);
PAINT PINK (-7890 5250);
DISPLAY INVISIBLE (-7890 5250);
FORCEPROP 2 LAST CDS_XR_PAGE_TITLE CR-338 : @T6G_MB_LIB.T6G(SCH_1):PAGE338
J 0
(-7890 5250);
DISPLAY 0.638298 (-7890 5250);
PAINT PINK (-7890 5250);
DISPLAY INVISIBLE (-7890 5250);
FORCEPROP 2 LAST CUSTOM_TXT_CDS <XR_PAGE_TITLE>
J 0
(-7890 5250);
DISPLAY 0.638298 (-7890 5250);
PAINT PINK (-7890 5250);
DISPLAY INVISIBLE (-7890 5250);
FORCEPROP 1 LAST COMMENT_BODY TRUE
J 0
(12 -13);
DISPLAY 0.978723 (12 -13);
PAINT GREEN (12 -13);
DISPLAY INVISIBLE (12 -13);
FORCEPROP 1 LAST Q_DEPT BU9
J 1
(-3763 49);
DISPLAY 1.957447 (-3763 49);
PAINT GREEN (-3763 49);
DISPLAY INVISIBLE (-3763 49);
FORCEPROP 0 LAST CDS_CON_LAST_MODIFIED Thu Aug 24 10:16:56 2023
J 0
(-1885 15);
DISPLAY INVISIBLE (-1885 15);
QUIT
